(kicad_pcb
	(version 20260206)
	(generator "pcbnew")
	(generator_version "10.0")
	(general
		(thickness 1.6)
		(legacy_teardrops no)
	)
	(paper "A4")
	(title_block
		(title "Wiwynn_Tioga_Pass_MB.brd")
		(comment 1 "Tioga Pass / footprints 1754-1757 of 4770")
	)
	(layers
		(0 "F.Cu" signal "TOP")
		(4 "In1.Cu" signal "L2GND")
		(6 "In2.Cu" signal "L3")
		(8 "In3.Cu" signal "L4GND")
		(10 "In4.Cu" signal "L5")
		(12 "In5.Cu" signal "L6GND")
		(14 "In6.Cu" signal "L7VCC")
		(16 "In7.Cu" signal "L8VCC")
		(18 "In8.Cu" signal "L9GND")
		(20 "In9.Cu" signal "L10")
		(22 "In10.Cu" signal "L11GND")
		(24 "In11.Cu" signal "L12")
		(26 "In12.Cu" signal "L13GND")
		(2 "B.Cu" signal "BOTTOM")
		(9 "F.Adhes" user "F.Adhesive")
		(11 "B.Adhes" user "B.Adhesive")
		(13 "F.Paste" user "Package Geometry/Pastemask Top")
		(15 "B.Paste" user "Package Geometry/Pastemask Bottom")
		(5 "F.SilkS" user "Ref Des/Silkscreen Top")
		(7 "B.SilkS" user "Ref Des/Silkscreen Bottom")
		(1 "F.Mask" user "Board Geometry/Soldermask Top")
		(3 "B.Mask" user "Board Geometry/Soldermask Bottom")
		(17 "Dwgs.User" user "User.Drawings")
		(19 "Cmts.User" user "User.Comments")
		(21 "Eco1.User" user "User.Eco1")
		(23 "Eco2.User" user "User.Eco2")
		(25 "Edge.Cuts" user "Board Geometry/Outline")
		(27 "Margin" user)
		(31 "F.CrtYd" user "Package Geometry/Place Bound Top")
		(29 "B.CrtYd" user "Package Geometry/Place Bound Bottom")
		(35 "F.Fab" user "Ref Des/Assembly Top")
		(33 "B.Fab" user "Ref Des/Assembly Bottom")
	)
	(footprint ""
		(layer "F.Cu")
		(at 465.328 -41.275)
		(property "Reference" "C9F3"
			(at 0 0 0)
			(layer "F.SilkS")
			(hide yes)
			(effects
				(font
					(size 1.27 1.27)
				)
			)
		)
		(property "Value" ""
			(at 0 0 0)
			(layer "F.Fab")
			(effects
				(font
					(size 1.27 1.27)
				)
			)
		)
		(duplicate_pad_numbers_are_jumpers no)
		(fp_poly
			(pts
				(xy -0.4953 -0.2032) (xy 0.4953 -0.2032) (xy 0.4953 1.6002) (xy -0.4953 1.6002)
			)
			(stroke
				(width 0)
				(type default)
			)
			(fill no)
			(layer "F.CrtYd")
		)
		(fp_line
			(start -0.4953 -0.2032)
			(end 0.4953 -0.2032)
			(stroke
				(width 0.1)
				(type default)
			)
			(layer "F.Fab")
		)
		(fp_line
			(start -0.4953 1.6002)
			(end -0.4953 -0.2032)
			(stroke
				(width 0.1)
				(type default)
			)
			(layer "F.Fab")
		)
		(fp_line
			(start 0.4953 -0.2032)
			(end 0.4953 1.6002)
			(stroke
				(width 0.1)
				(type default)
			)
			(layer "F.Fab")
		)
		(fp_line
			(start 0.4953 1.6002)
			(end -0.4953 1.6002)
			(stroke
				(width 0.1)
				(type default)
			)
			(layer "F.Fab")
		)
		(pad "1" smd rect
			(at 0 0)
			(size 0.762 0.889)
			(layers "F.Cu" "F.Mask" "F.Paste")
			(net "P3V3_STBY")
		)
		(pad "2" smd rect
			(at 0 1.397)
			(size 0.762 0.889)
			(layers "F.Cu" "F.Mask" "F.Paste")
			(net "GND")
		)
		(zone
			(layer "F.Cu")
			(hatch none 0.5)
			(connect_pads
				(clearance 0)
			)
			(min_thickness 0.25)
			(keepout
				(tracks not_allowed)
				(vias allowed)
				(pads allowed)
				(copperpour not_allowed)
				(footprints allowed)
			)
			(placement
				(enabled no)
				(sheetname "")
			)
			(fill
				(thermal_gap 0.5)
				(thermal_bridge_width 0.5)
				(island_removal_mode 0)
			)
			(polygon
				(pts
					(xy 464.947 -40.8305) (xy 465.709 -40.8305) (xy 465.709 -40.3225) (xy 464.947 -40.3225)
				)
			)
		)
	)
	(footprint ""
		(layer "F.Cu")
		(at 337.82 -128.2065 180)
		(property "Reference" "C7B13"
			(at 0 0 180)
			(layer "F.SilkS")
			(hide yes)
			(effects
				(font
					(size 1.27 1.27)
				)
			)
		)
		(property "Value" ""
			(at 0 0 180)
			(layer "F.Fab")
			(effects
				(font
					(size 1.27 1.27)
				)
			)
		)
		(duplicate_pad_numbers_are_jumpers no)
		(fp_poly
			(pts
				(xy 0.3048 -0.1016) (xy 0.3048 0.9906) (xy -0.3048 0.9906) (xy -0.3048 -0.1016)
			)
			(stroke
				(width 0)
				(type default)
			)
			(fill no)
			(layer "F.CrtYd")
		)
		(fp_line
			(start 0.3048 0.9906)
			(end 0.3048 -0.1016)
			(stroke
				(width 0.1)
				(type default)
			)
			(layer "F.Fab")
		)
		(fp_line
			(start 0.3048 -0.1016)
			(end -0.3048 -0.1016)
			(stroke
				(width 0.1)
				(type default)
			)
			(layer "F.Fab")
		)
		(fp_line
			(start -0.3048 0.9906)
			(end 0.3048 0.9906)
			(stroke
				(width 0.1)
				(type default)
			)
			(layer "F.Fab")
		)
		(fp_line
			(start -0.3048 -0.1016)
			(end -0.3048 0.9906)
			(stroke
				(width 0.1)
				(type default)
			)
			(layer "F.Fab")
		)
		(pad "1" smd rect
			(at 0 0 180)
			(size 0.508 0.508)
			(layers "F.Cu" "F.Mask" "F.Paste")
			(net "VR_COMP_PVPP_DEF")
		)
		(pad "2" smd rect
			(at 0 0.889 180)
			(size 0.508 0.508)
			(layers "F.Cu" "F.Mask" "F.Paste")
			(net "VR_FB_PVPP_DEF")
		)
		(zone
			(layer "F.Cu")
			(hatch none 0.5)
			(connect_pads
				(clearance 0)
			)
			(min_thickness 0.25)
			(keepout
				(tracks not_allowed)
				(vias allowed)
				(pads allowed)
				(copperpour not_allowed)
				(footprints allowed)
			)
			(placement
				(enabled no)
				(sheetname "")
			)
			(fill
				(thermal_gap 0.5)
				(thermal_bridge_width 0.5)
				(island_removal_mode 0)
			)
			(polygon
				(pts
					(xy 338.074 -128.8415) (xy 337.566 -128.8415) (xy 337.566 -128.4605) (xy 338.074 -128.4605)
				)
			)
		)
		(zone
			(layer "F.Cu")
			(hatch none 0.5)
			(connect_pads
				(clearance 0)
			)
			(min_thickness 0.25)
			(keepout
				(tracks allowed)
				(vias not_allowed)
				(pads allowed)
				(copperpour not_allowed)
				(footprints allowed)
			)
			(placement
				(enabled no)
				(sheetname "")
			)
			(fill
				(thermal_gap 0.5)
				(thermal_bridge_width 0.5)
				(island_removal_mode 0)
			)
			(polygon
				(pts
					(xy 338.074 -128.4605) (xy 337.566 -128.4605) (xy 337.566 -128.8415) (xy 338.074 -128.8415)
				)
			)
		)
	)
	(footprint ""
		(layer "F.Cu")
		(at 173.7487 -69.723 90)
		(property "Reference" "C4D36"
			(at 0 0 90)
			(layer "F.SilkS")
			(hide yes)
			(effects
				(font
					(size 1.27 1.27)
				)
			)
		)
		(property "Value" ""
			(at 0 0 90)
			(layer "F.Fab")
			(effects
				(font
					(size 1.27 1.27)
				)
			)
		)
		(duplicate_pad_numbers_are_jumpers no)
		(fp_poly
			(pts
				(xy 0.3048 -0.1016) (xy 0.3048 0.9906) (xy -0.3048 0.9906) (xy -0.3048 -0.1016)
			)
			(stroke
				(width 0)
				(type default)
			)
			(fill no)
			(layer "F.CrtYd")
		)
		(fp_line
			(start 0.3048 -0.1016)
			(end -0.3048 -0.1016)
			(stroke
				(width 0.1)
				(type default)
			)
			(layer "F.Fab")
		)
		(fp_line
			(start -0.3048 -0.1016)
			(end -0.3048 0.9906)
			(stroke
				(width 0.1)
				(type default)
			)
			(layer "F.Fab")
		)
		(fp_line
			(start 0.3048 0.9906)
			(end 0.3048 -0.1016)
			(stroke
				(width 0.1)
				(type default)
			)
			(layer "F.Fab")
		)
		(fp_line
			(start -0.3048 0.9906)
			(end 0.3048 0.9906)
			(stroke
				(width 0.1)
				(type default)
			)
			(layer "F.Fab")
		)
		(pad "1" smd rect
			(at 0 0 90)
			(size 0.508 0.508)
			(layers "F.Cu" "F.Mask" "F.Paste")
			(net "VR_PVCCIO_CPU1_VDD")
		)
		(pad "2" smd rect
			(at 0 0.889 90)
			(size 0.508 0.508)
			(layers "F.Cu" "F.Mask" "F.Paste")
			(net "GND")
		)
		(zone
			(layer "F.Cu")
			(hatch none 0.5)
			(connect_pads
				(clearance 0)
			)
			(min_thickness 0.25)
			(keepout
				(tracks allowed)
				(vias not_allowed)
				(pads allowed)
				(copperpour not_allowed)
				(footprints allowed)
			)
			(placement
				(enabled no)
				(sheetname "")
			)
			(fill
				(thermal_gap 0.5)
				(thermal_bridge_width 0.5)
				(island_removal_mode 0)
			)
			(polygon
				(pts
					(xy 174.0027 -69.469) (xy 174.0027 -69.977) (xy 174.3837 -69.977) (xy 174.3837 -69.469)
				)
			)
		)
		(zone
			(layer "F.Cu")
			(hatch none 0.5)
			(connect_pads
				(clearance 0)
			)
			(min_thickness 0.25)
			(keepout
				(tracks not_allowed)
				(vias allowed)
				(pads allowed)
				(copperpour not_allowed)
				(footprints allowed)
			)
			(placement
				(enabled no)
				(sheetname "")
			)
			(fill
				(thermal_gap 0.5)
				(thermal_bridge_width 0.5)
				(island_removal_mode 0)
			)
			(polygon
				(pts
					(xy 174.3837 -69.469) (xy 174.3837 -69.977) (xy 174.0027 -69.977) (xy 174.0027 -69.469)
				)
			)
		)
	)
	(footprint ""
		(layer "F.Cu")
		(at 116.332 -76.327 90)
		(property "Reference" "R3D12"
			(at 0 0 90)
			(layer "F.SilkS")
			(hide yes)
			(effects
				(font
					(size 1.27 1.27)
				)
			)
		)
		(property "Value" ""
			(at 0 0 90)
			(layer "F.Fab")
			(effects
				(font
					(size 1.27 1.27)
				)
			)
		)
		(duplicate_pad_numbers_are_jumpers no)
		(fp_poly
			(pts
				(xy -0.2794 -0.1016) (xy 0.2794 -0.1016) (xy 0.2794 0.9906) (xy -0.2794 0.9906)
			)
			(stroke
				(width 0)
				(type default)
			)
			(fill no)
			(layer "F.CrtYd")
		)
		(fp_line
			(start 0.2794 -0.1016)
			(end -0.2794 -0.1016)
			(stroke
				(width 0.1)
				(type default)
			)
			(layer "F.Fab")
		)
		(fp_line
			(start -0.2794 -0.1016)
			(end -0.2794 0.9906)
			(stroke
				(width 0.1)
				(type default)
			)
			(layer "F.Fab")
		)
		(fp_line
			(start 0.2794 0.9906)
			(end 0.2794 -0.1016)
			(stroke
				(width 0.1)
				(type default)
			)
			(layer "F.Fab")
		)
		(fp_line
			(start -0.2794 0.9906)
			(end 0.2794 0.9906)
			(stroke
				(width 0.1)
				(type default)
			)
			(layer "F.Fab")
		)
		(pad "1" smd rect
			(at 0 0 90)
			(size 0.508 0.508)
			(layers "F.Cu" "F.Mask" "F.Paste")
			(net "GND")
		)
		(pad "2" smd rect
			(at 0 0.889 90)
			(size 0.508 0.508)
			(layers "F.Cu" "F.Mask" "F.Paste")
			(net "PD_CPU1_TXT_PLTEN")
		)
		(zone
			(layer "F.Cu")
			(hatch none 0.5)
			(connect_pads
				(clearance 0)
			)
			(min_thickness 0.25)
			(keepout
				(tracks allowed)
				(vias not_allowed)
				(pads allowed)
				(copperpour not_allowed)
				(footprints allowed)
			)
			(placement
				(enabled no)
				(sheetname "")
			)
			(fill
				(thermal_gap 0.5)
				(thermal_bridge_width 0.5)
				(island_removal_mode 0)
			)
			(polygon
				(pts
					(xy 116.586 -76.073) (xy 116.586 -76.581) (xy 116.967 -76.581) (xy 116.967 -76.073)
				)
			)
		)
		(zone
			(layer "F.Cu")
			(hatch none 0.5)
			(connect_pads
				(clearance 0)
			)
			(min_thickness 0.25)
			(keepout
				(tracks not_allowed)
				(vias allowed)
				(pads allowed)
				(copperpour not_allowed)
				(footprints allowed)
			)
			(placement
				(enabled no)
				(sheetname "")
			)
			(fill
				(thermal_gap 0.5)
				(thermal_bridge_width 0.5)
				(island_removal_mode 0)
			)
			(polygon
				(pts
					(xy 116.967 -76.073) (xy 116.967 -76.581) (xy 116.586 -76.581) (xy 116.586 -76.073)
				)
			)
		)
	)
)
